FILE_TYPE = MACRO_DRAWING;
SET COLOR_WIRE YELLOW;
SET COLOR_PROP ORANGE;
SET COLOR_DOT WHITE;
SET COLOR_ARC YELLOW;
SET COLOR_BODY GREEN;
SET COLOR_NOTE PURPLE;
SET PROP_DISPLAY VALUE;
SET PAGE_NUMBER P7;
SET PATH_NUMBER P0;
FORCEADD QUANTA_TITLE_BLOCK_C..1
(5350 -1475);
FORCEPROP 0 LAST CDS_CON_LAST_MODIFIED Fri Aug 25 17:25:35 2023
J 0
(3465 -1460);
DISPLAY INVISIBLE (3465 -1460);
FORCEPROP 2 LAST Q_DEPT 
J 1
(1587 -1426);
DISPLAY 1.957447 (1587 -1426);
PAINT GREEN (1587 -1426);
FORCEPROP 1 LAST CUSTOM_TXT_CDS <CON_LAST_MODIFIED>
J 0
(3465 -1460);
DISPLAY 0.978723 (3465 -1460);
FORCEPROP 2 LAST CUSTOM_TXT_CDS <XR_PAGE_TITLE>
J 0
(-2540 3775);
DISPLAY 0.638298 (-2540 3775);
PAINT PINK (-2540 3775);
DISPLAY INVISIBLE (-2540 3775);
FORCEPROP 1 LAST CUSTOM_TXT_CDS <NAME_2>
J 0
(2175 -1425);
FORCEPROP 1 LAST CUSTOM_TXT_CDS <NAME_1>
J 0
(2175 -1300);
FORCEPROP 1 LAST CUSTOM_TXT_CDS <Q_NUMBER>
J 0
(3947 -1372);
DISPLAY 1.212766 (3947 -1372);
FORCEPROP 1 LAST CUSTOM_TXT_CDS <Q_PROJ>
J 0
(2968 -1373);
DISPLAY 1.212766 (2968 -1373);
FORCEPROP 1 LAST CUSTOM_TXT_CDS <Q_REV>
J 0
(5166 -1372);
DISPLAY 1.212766 (5166 -1372);
FORCEPROP 1 LAST CUSTOM_TXT_CDS <CON_PAGE_NUM> OF <CON_TOTAL_PAGES>
J 0
(4904 -1457);
DISPLAY 0.978723 (4904 -1457);
FORCEPROP 1 LAST Q_TITLE JTAG DIAGRAM
J 0
(-4016 -1449);
DISPLAY 2.446809 (-4016 -1449);
PAINT GREEN (-4016 -1449);
FORCEPROP 2 LAST PAGE_BORDER TRUE
J 0
(-2540 3775);
DISPLAY 0.638298 (-2540 3775);
PAINT PINK (-2540 3775);
DISPLAY INVISIBLE (-2540 3775);
FORCEPROP 1 LAST CDS_LMAN_SYM_OUTLINE -9475,6775,100,-125
J 0
(5350 -1475);
DISPLAY 0.468085 (5350 -1475);
PAINT GREEN (5350 -1475);
DISPLAY INVISIBLE (5350 -1475);
FORCEPROP 2 LAST CDS_LIB pure_quanta
J 0
(5350 -1475);
DISPLAY INVISIBLE (5350 -1475);
FORCEPROP 1 LAST COMMENT_BODY TRUE
J 0
(5362 -1488);
DISPLAY 0.978723 (5362 -1488);
PAINT PEACH (5362 -1488);
DISPLAY INVISIBLE (5362 -1488);
FORCEPROP 2 LAST CDS_XR_PAGE_TITLE CR-7 : @SCM_LIB.SCM(SCH_1):PAGE7
J 0
(-2540 3775);
DISPLAY 0.638298 (-2540 3775);
PAINT PINK (-2540 3775);
DISPLAY INVISIBLE (-2540 3775);
FORCENOTE
$CDS_IMAGE|F0T_JTAG_20211125-JTAG.jpg|6794|6175
(350 1950) 0;
DISPLAY LEFT (350 1950);
QUIT
